# T6G (Grand Teton) — schematic netlist excerpt (pin names and nets, part order shuffled) for the footprints in the layout excerpt that follows; sources: Cadence DE-HDL packaged netlist, KiCad conversion of 04192023_DAF0TMB3IC0_F0TG_MB_C_brd_V02_OCP.brd

R6139  Q_RES  1K 1% EMPTY  pkg 0402LF  page 84 : A = P3V3_AUX ; B = FM_BOARD_BMC_SKU_ID1
C1996  Q_CAP_DIFFBUS  DIFF BUS_0.22UF 6.3V 20% X6S  pkg C0201  page 67 : \1\ = P3E_CPU0_P4_TX_C_DN<0> ; \2\ = P3E_CPU0_P4_TX_DN<0>
PC413  Q_CAP  0.22UF 16V 10% X7R  pkg 0402  page 219 : A = SW_PVDDCR_CPU1_P1_BOOT4_R ; B = SW_PVDDCR_CPU1_P1_BOOTR4

(kicad_pcb
	(version 20260206)
	(generator "pcbnew")
	(generator_version "10.0")
	(general
		(thickness 1.6)
		(legacy_teardrops no)
	)
	(paper "A4")
	(title_block
		(title "04192023_DAF0TMB3IC0_F0TG_MB_C_brd_V02_OCP.brd")
		(comment 1 "Grand Teton / footprints 2615-2617 of 8354")
	)
	(layers
		(0 "F.Cu" signal "TOP")
		(4 "In1.Cu" signal "GND")
		(6 "In2.Cu" signal "IN1")
		(8 "In3.Cu" signal "GND1")
		(10 "In4.Cu" signal "IN2")
		(12 "In5.Cu" signal "GND2")
		(14 "In6.Cu" signal "IN3")
		(16 "In7.Cu" signal "GND3")
		(18 "In8.Cu" signal "VCC")
		(20 "In9.Cu" signal "VCC1")
		(22 "In10.Cu" signal "GND4")
		(24 "In11.Cu" signal "IN4")
		(26 "In12.Cu" signal "GND5")
		(28 "In13.Cu" signal "IN5")
		(30 "In14.Cu" signal "GND6")
		(32 "In15.Cu" signal "IN6")
		(34 "In16.Cu" signal "GND7")
		(2 "B.Cu" signal "BOTTOM")
		(9 "F.Adhes" user "F.Adhesive")
		(11 "B.Adhes" user "B.Adhesive")
		(13 "F.Paste" user "Package Geometry/Pastemask Top")
		(15 "B.Paste" user "Package Geometry/Pastemask Bottom")
		(5 "F.SilkS" user "Ref Des/Silkscreen Top")
		(7 "B.SilkS" user "Ref Des/Silkscreen Bottom")
		(1 "F.Mask" user "Board Geometry/Soldermask Top")
		(3 "B.Mask" user "Board Geometry/Soldermask Bottom")
		(17 "Dwgs.User" user "User.Drawings")
		(19 "Cmts.User" user "User.Comments")
		(21 "Eco1.User" user "User.Eco1")
		(23 "Eco2.User" user "User.Eco2")
		(25 "Edge.Cuts" user "Board Geometry/Outline")
		(27 "Margin" user)
		(31 "F.CrtYd" user "Package Geometry/Place Bound Top")
		(29 "B.CrtYd" user "Package Geometry/Place Bound Bottom")
		(35 "F.Fab" user "Ref Des/Assembly Top")
		(33 "B.Fab" user "Ref Des/Assembly Bottom")
	)
	(footprint ""
		(layer "F.Cu")
		(at 168.355518 -125.762004)
		(property "Reference" "R6139"
			(at 0 0 0)
			(layer "F.SilkS")
			(hide yes)
			(effects
				(font
					(size 1.27 1.27)
				)
			)
		)
		(property "Value" ""
			(at 0 0 0)
			(layer "F.Fab")
			(effects
				(font
					(size 1.27 1.27)
				)
			)
		)
		(duplicate_pad_numbers_are_jumpers no)
		(fp_line
			(start -0.7874 -0.4064)
			(end 0.7874 -0.4064)
			(stroke
				(width 0.1524)
				(type default)
			)
			(layer "F.SilkS")
		)
		(fp_line
			(start -0.7874 0.4064)
			(end -0.7874 -0.4064)
			(stroke
				(width 0.1524)
				(type default)
			)
			(layer "F.SilkS")
		)
		(fp_line
			(start 0.7874 -0.4064)
			(end 0.7874 0.4064)
			(stroke
				(width 0.1524)
				(type default)
			)
			(layer "F.SilkS")
		)
		(fp_line
			(start 0.7874 0.4064)
			(end -0.7874 0.4064)
			(stroke
				(width 0.1524)
				(type default)
			)
			(layer "F.SilkS")
		)
		(fp_line
			(start -0.67945 -0.305054)
			(end -0.12065 -0.305054)
			(stroke
				(width 0.1)
				(type default)
			)
			(layer "F.Fab")
		)
		(fp_line
			(start -0.67945 0.3048)
			(end -0.67945 -0.305054)
			(stroke
				(width 0.1)
				(type default)
			)
			(layer "F.Fab")
		)
		(fp_line
			(start -0.12065 -0.305054)
			(end -0.12065 -0.2794)
			(stroke
				(width 0.1)
				(type default)
			)
			(layer "F.Fab")
		)
		(fp_line
			(start -0.12065 -0.2794)
			(end 0.12065 -0.2794)
			(stroke
				(width 0.1)
				(type default)
			)
			(layer "F.Fab")
		)
		(fp_line
			(start -0.12065 0.2794)
			(end -0.12065 0.3048)
			(stroke
				(width 0.1)
				(type default)
			)
			(layer "F.Fab")
		)
		(fp_line
			(start -0.12065 0.3048)
			(end -0.67945 0.3048)
			(stroke
				(width 0.1)
				(type default)
			)
			(layer "F.Fab")
		)
		(fp_line
			(start 0.120396 0.2794)
			(end -0.12065 0.2794)
			(stroke
				(width 0.1)
				(type default)
			)
			(layer "F.Fab")
		)
		(fp_line
			(start 0.120396 0.3048)
			(end 0.120396 0.2794)
			(stroke
				(width 0.1)
				(type default)
			)
			(layer "F.Fab")
		)
		(fp_line
			(start 0.12065 -0.3048)
			(end 0.67945 -0.3048)
			(stroke
				(width 0.1)
				(type default)
			)
			(layer "F.Fab")
		)
		(fp_line
			(start 0.12065 -0.2794)
			(end 0.12065 -0.3048)
			(stroke
				(width 0.1)
				(type default)
			)
			(layer "F.Fab")
		)
		(fp_line
			(start 0.67945 -0.3048)
			(end 0.67945 0.3048)
			(stroke
				(width 0.1)
				(type default)
			)
			(layer "F.Fab")
		)
		(fp_line
			(start 0.67945 0.3048)
			(end 0.120396 0.3048)
			(stroke
				(width 0.1)
				(type default)
			)
			(layer "F.Fab")
		)
		(pad "1" smd circle
			(at -0.40005 0)
			(size 0 0)
			(layers "F.Cu" "F.Mask" "F.Paste")
			(net "P3V3_AUX")
		)
		(pad "2" smd circle
			(at 0.40005 0)
			(size 0 0)
			(layers "F.Cu" "F.Mask" "F.Paste")
			(net "FM_BOARD_BMC_SKU_ID1")
		)
	)
	(footprint ""
		(layer "F.Cu")
		(at 63.660528 -351.372932 -90)
		(property "Reference" "PC413"
			(at 0 0 270)
			(layer "F.SilkS")
			(hide yes)
			(effects
				(font
					(size 1.27 1.27)
				)
			)
		)
		(property "Value" ""
			(at 0 0 270)
			(layer "F.Fab")
			(effects
				(font
					(size 1.27 1.27)
				)
			)
		)
		(duplicate_pad_numbers_are_jumpers no)
		(fp_line
			(start -0.7874 0.4064)
			(end -0.7874 -0.4064)
			(stroke
				(width 0.1524)
				(type default)
			)
			(layer "F.SilkS")
		)
		(fp_line
			(start 0.7874 0.4064)
			(end -0.7874 0.4064)
			(stroke
				(width 0.1524)
				(type default)
			)
			(layer "F.SilkS")
		)
		(fp_line
			(start -0.7874 -0.4064)
			(end 0.7874 -0.4064)
			(stroke
				(width 0.1524)
				(type default)
			)
			(layer "F.SilkS")
		)
		(fp_line
			(start 0.7874 -0.4064)
			(end 0.7874 0.4064)
			(stroke
				(width 0.1524)
				(type default)
			)
			(layer "F.SilkS")
		)
		(fp_line
			(start -0.67945 0.3048)
			(end -0.67945 -0.305054)
			(stroke
				(width 0.1)
				(type default)
			)
			(layer "F.Fab")
		)
		(fp_line
			(start -0.12065 0.3048)
			(end -0.67945 0.3048)
			(stroke
				(width 0.1)
				(type default)
			)
			(layer "F.Fab")
		)
		(fp_line
			(start 0.120396 0.3048)
			(end 0.120396 0.2794)
			(stroke
				(width 0.1)
				(type default)
			)
			(layer "F.Fab")
		)
		(fp_line
			(start 0.67945 0.3048)
			(end 0.120396 0.3048)
			(stroke
				(width 0.1)
				(type default)
			)
			(layer "F.Fab")
		)
		(fp_line
			(start -0.12065 0.2794)
			(end -0.12065 0.3048)
			(stroke
				(width 0.1)
				(type default)
			)
			(layer "F.Fab")
		)
		(fp_line
			(start 0.120396 0.2794)
			(end -0.12065 0.2794)
			(stroke
				(width 0.1)
				(type default)
			)
			(layer "F.Fab")
		)
		(fp_line
			(start -0.12065 -0.2794)
			(end 0.12065 -0.2794)
			(stroke
				(width 0.1)
				(type default)
			)
			(layer "F.Fab")
		)
		(fp_line
			(start 0.12065 -0.2794)
			(end 0.12065 -0.3048)
			(stroke
				(width 0.1)
				(type default)
			)
			(layer "F.Fab")
		)
		(fp_line
			(start 0.12065 -0.3048)
			(end 0.67945 -0.3048)
			(stroke
				(width 0.1)
				(type default)
			)
			(layer "F.Fab")
		)
		(fp_line
			(start 0.67945 -0.3048)
			(end 0.67945 0.3048)
			(stroke
				(width 0.1)
				(type default)
			)
			(layer "F.Fab")
		)
		(fp_line
			(start -0.67945 -0.305054)
			(end -0.12065 -0.305054)
			(stroke
				(width 0.1)
				(type default)
			)
			(layer "F.Fab")
		)
		(fp_line
			(start -0.12065 -0.305054)
			(end -0.12065 -0.2794)
			(stroke
				(width 0.1)
				(type default)
			)
			(layer "F.Fab")
		)
		(pad "1" smd circle
			(at -0.40005 0 270)
			(size 0 0)
			(layers "F.Cu" "F.Mask" "F.Paste")
			(net "SW_PVDDCR_CPU1_P1_BOOT4_R")
		)
		(pad "2" smd circle
			(at 0.40005 0 270)
			(size 0 0)
			(layers "F.Cu" "F.Mask" "F.Paste")
			(net "SW_PVDDCR_CPU1_P1_BOOTR4")
		)
	)
	(footprint ""
		(layer "F.Cu")
		(at 239.152684 -52.92725)
		(property "Reference" "C1996"
			(at 0 0 0)
			(layer "F.SilkS")
			(hide yes)
			(effects
				(font
					(size 1.27 1.27)
				)
			)
		)
		(property "Value" ""
			(at 0 0 0)
			(layer "F.Fab")
			(effects
				(font
					(size 1.27 1.27)
				)
			)
		)
		(duplicate_pad_numbers_are_jumpers no)
		(fp_line
			(start -0.299974 -0.150114)
			(end 0.299974 -0.150114)
			(stroke
				(width 0.1)
				(type default)
			)
			(layer "F.Fab")
		)
		(fp_line
			(start -0.299974 0.150114)
			(end -0.299974 -0.150114)
			(stroke
				(width 0.1)
				(type default)
			)
			(layer "F.Fab")
		)
		(fp_line
			(start 0.299974 -0.150114)
			(end 0.299974 0.150114)
			(stroke
				(width 0.1)
				(type default)
			)
			(layer "F.Fab")
		)
		(fp_line
			(start 0.299974 0.150114)
			(end -0.299974 0.150114)
			(stroke
				(width 0.1)
				(type default)
			)
			(layer "F.Fab")
		)
		(pad "1" smd rect
			(at -0.2667 0)
			(size 0.3048 0.381)
			(layers "F.Cu" "F.Mask" "F.Paste")
			(net "P3E_CPU0_P4_TX_C_DN<0>")
		)
		(pad "2" smd rect
			(at 0.2667 0)
			(size 0.3048 0.381)
			(layers "F.Cu" "F.Mask" "F.Paste")
			(net "P3E_CPU0_P4_TX_DN<0>")
		)
	)
)
